# BASEBOARD_FAB2 (Tioga Pass) — schematic netlist excerpt (pin names and nets, part order shuffled) for the footprints in the layout excerpt that follows; sources: Cadence DE-HDL packaged netlist, KiCad conversion of Wiwynn_Tioga_Pass_MB.brd

CT68  CAP  1000PF 50V 10% X7R  pkg 0402LF  page 236 : A = VR_P1V05_PCH_STBY_PH1_PHASE_SW ; B = VR_P1V05_PCH_STBY_PH1_SW_RC
C832  CAP  0.22UF 16V 10% X7R  pkg 0402  page 244 : A = P3E_CPU0_PE1_PCH_TXN<11> ; B = P3E_CPU0_PE1_PCH_CON_TXN<11>
R7F28  RES  10.0K 1% CHIP  pkg 0402  page 153 : A = P3V3_STBY ; B = PU_BIOS_SPI_WP0_N

(kicad_pcb
	(version 20260206)
	(generator "pcbnew")
	(generator_version "10.0")
	(general
		(thickness 1.6)
		(legacy_teardrops no)
	)
	(paper "A4")
	(title_block
		(title "Wiwynn_Tioga_Pass_MB.brd")
		(comment 1 "Tioga Pass / footprints 432-434 of 4770")
	)
	(layers
		(0 "F.Cu" signal "TOP")
		(4 "In1.Cu" signal "L2GND")
		(6 "In2.Cu" signal "L3")
		(8 "In3.Cu" signal "L4GND")
		(10 "In4.Cu" signal "L5")
		(12 "In5.Cu" signal "L6GND")
		(14 "In6.Cu" signal "L7VCC")
		(16 "In7.Cu" signal "L8VCC")
		(18 "In8.Cu" signal "L9GND")
		(20 "In9.Cu" signal "L10")
		(22 "In10.Cu" signal "L11GND")
		(24 "In11.Cu" signal "L12")
		(26 "In12.Cu" signal "L13GND")
		(2 "B.Cu" signal "BOTTOM")
		(9 "F.Adhes" user "F.Adhesive")
		(11 "B.Adhes" user "B.Adhesive")
		(13 "F.Paste" user "Package Geometry/Pastemask Top")
		(15 "B.Paste" user "Package Geometry/Pastemask Bottom")
		(5 "F.SilkS" user "Ref Des/Silkscreen Top")
		(7 "B.SilkS" user "Ref Des/Silkscreen Bottom")
		(1 "F.Mask" user "Board Geometry/Soldermask Top")
		(3 "B.Mask" user "Board Geometry/Soldermask Bottom")
		(17 "Dwgs.User" user "User.Drawings")
		(19 "Cmts.User" user "User.Comments")
		(21 "Eco1.User" user "User.Eco1")
		(23 "Eco2.User" user "User.Eco2")
		(25 "Edge.Cuts" user "Board Geometry/Outline")
		(27 "Margin" user)
		(31 "F.CrtYd" user "Package Geometry/Place Bound Top")
		(29 "B.CrtYd" user "Package Geometry/Place Bound Bottom")
		(35 "F.Fab" user "Ref Des/Assembly Top")
		(33 "B.Fab" user "Ref Des/Assembly Bottom")
	)
	(footprint ""
		(layer "F.Cu")
		(at 383.794 -55.4355 180)
		(property "Reference" "R7F28"
			(at 0 0 180)
			(layer "F.SilkS")
			(hide yes)
			(effects
				(font
					(size 1.27 1.27)
				)
			)
		)
		(property "Value" ""
			(at 0 0 180)
			(layer "F.Fab")
			(effects
				(font
					(size 1.27 1.27)
				)
			)
		)
		(duplicate_pad_numbers_are_jumpers no)
		(fp_poly
			(pts
				(xy -0.2794 -0.1016) (xy 0.2794 -0.1016) (xy 0.2794 0.9906) (xy -0.2794 0.9906)
			)
			(stroke
				(width 0)
				(type default)
			)
			(fill no)
			(layer "F.CrtYd")
		)
		(fp_line
			(start 0.2794 0.9906)
			(end 0.2794 -0.1016)
			(stroke
				(width 0.1)
				(type default)
			)
			(layer "F.Fab")
		)
		(fp_line
			(start 0.2794 -0.1016)
			(end -0.2794 -0.1016)
			(stroke
				(width 0.1)
				(type default)
			)
			(layer "F.Fab")
		)
		(fp_line
			(start -0.2794 0.9906)
			(end 0.2794 0.9906)
			(stroke
				(width 0.1)
				(type default)
			)
			(layer "F.Fab")
		)
		(fp_line
			(start -0.2794 -0.1016)
			(end -0.2794 0.9906)
			(stroke
				(width 0.1)
				(type default)
			)
			(layer "F.Fab")
		)
		(pad "1" smd rect
			(at 0 0 180)
			(size 0.508 0.508)
			(layers "F.Cu" "F.Mask" "F.Paste")
			(net "P3V3_STBY")
		)
		(pad "2" smd rect
			(at 0 0.889 180)
			(size 0.508 0.508)
			(layers "F.Cu" "F.Mask" "F.Paste")
			(net "PU_BIOS_SPI_WP0_N")
		)
		(zone
			(layer "F.Cu")
			(hatch none 0.5)
			(connect_pads
				(clearance 0)
			)
			(min_thickness 0.25)
			(keepout
				(tracks not_allowed)
				(vias allowed)
				(pads allowed)
				(copperpour not_allowed)
				(footprints allowed)
			)
			(placement
				(enabled no)
				(sheetname "")
			)
			(fill
				(thermal_gap 0.5)
				(thermal_bridge_width 0.5)
				(island_removal_mode 0)
			)
			(polygon
				(pts
					(xy 384.048 -56.0705) (xy 383.54 -56.0705) (xy 383.54 -55.6895) (xy 384.048 -55.6895)
				)
			)
		)
		(zone
			(layer "F.Cu")
			(hatch none 0.5)
			(connect_pads
				(clearance 0)
			)
			(min_thickness 0.25)
			(keepout
				(tracks allowed)
				(vias not_allowed)
				(pads allowed)
				(copperpour not_allowed)
				(footprints allowed)
			)
			(placement
				(enabled no)
				(sheetname "")
			)
			(fill
				(thermal_gap 0.5)
				(thermal_bridge_width 0.5)
				(island_removal_mode 0)
			)
			(polygon
				(pts
					(xy 384.048 -55.6895) (xy 383.54 -55.6895) (xy 383.54 -56.0705) (xy 384.048 -56.0705)
				)
			)
		)
	)
	(footprint ""
		(layer "F.Cu")
		(at 381.51562 -147.928076 180)
		(property "Reference" "CT68"
			(at -0.8382 -0.67818 180)
			(unlocked yes)
			(layer "F.SilkS")
			(effects
				(font
					(size 0.4064 0.254)
					(thickness 0.1524)
				)
				(justify left)
			)
		)
		(property "Value" ""
			(at 0 0 180)
			(layer "F.Fab")
			(effects
				(font
					(size 1.27 1.27)
				)
			)
		)
		(duplicate_pad_numbers_are_jumpers no)
		(fp_poly
			(pts
				(xy 0.3048 -0.1016) (xy 0.3048 0.9906) (xy -0.3048 0.9906) (xy -0.3048 -0.1016)
			)
			(stroke
				(width 0)
				(type default)
			)
			(fill no)
			(layer "F.CrtYd")
		)
		(fp_line
			(start 0.3048 0.9906)
			(end 0.3048 -0.1016)
			(stroke
				(width 0.1)
				(type default)
			)
			(layer "F.Fab")
		)
		(fp_line
			(start 0.3048 -0.1016)
			(end -0.3048 -0.1016)
			(stroke
				(width 0.1)
				(type default)
			)
			(layer "F.Fab")
		)
		(fp_line
			(start -0.3048 0.9906)
			(end 0.3048 0.9906)
			(stroke
				(width 0.1)
				(type default)
			)
			(layer "F.Fab")
		)
		(fp_line
			(start -0.3048 -0.1016)
			(end -0.3048 0.9906)
			(stroke
				(width 0.1)
				(type default)
			)
			(layer "F.Fab")
		)
		(pad "1" smd rect
			(at 0 0 180)
			(size 0.508 0.508)
			(layers "F.Cu" "F.Mask" "F.Paste")
			(net "VR_P1V05_PCH_STBY_PH1_PHASE_SW")
		)
		(pad "2" smd rect
			(at 0 0.889 180)
			(size 0.508 0.508)
			(layers "F.Cu" "F.Mask" "F.Paste")
			(net "VR_P1V05_PCH_STBY_PH1_SW_RC")
		)
		(zone
			(layer "F.Cu")
			(hatch none 0.5)
			(connect_pads
				(clearance 0)
			)
			(min_thickness 0.25)
			(keepout
				(tracks not_allowed)
				(vias allowed)
				(pads allowed)
				(copperpour not_allowed)
				(footprints allowed)
			)
			(placement
				(enabled no)
				(sheetname "")
			)
			(fill
				(thermal_gap 0.5)
				(thermal_bridge_width 0.5)
				(island_removal_mode 0)
			)
			(polygon
				(pts
					(xy 381.76962 -148.563076) (xy 381.26162 -148.563076) (xy 381.26162 -148.182076) (xy 381.76962 -148.182076)
				)
			)
		)
		(zone
			(layer "F.Cu")
			(hatch none 0.5)
			(connect_pads
				(clearance 0)
			)
			(min_thickness 0.25)
			(keepout
				(tracks allowed)
				(vias not_allowed)
				(pads allowed)
				(copperpour not_allowed)
				(footprints allowed)
			)
			(placement
				(enabled no)
				(sheetname "")
			)
			(fill
				(thermal_gap 0.5)
				(thermal_bridge_width 0.5)
				(island_removal_mode 0)
			)
			(polygon
				(pts
					(xy 381.76962 -148.182076) (xy 381.26162 -148.182076) (xy 381.26162 -148.563076) (xy 381.76962 -148.563076)
				)
			)
		)
	)
	(footprint ""
		(layer "F.Cu")
		(at 323.0245 -117.222016 -90)
		(property "Reference" "C832"
			(at -0.8382 -0.67818 270)
			(unlocked yes)
			(layer "F.SilkS")
			(effects
				(font
					(size 0.4064 0.254)
					(thickness 0.1524)
				)
				(justify left)
			)
		)
		(property "Value" ""
			(at 0 0 270)
			(layer "F.Fab")
			(effects
				(font
					(size 1.27 1.27)
				)
			)
		)
		(duplicate_pad_numbers_are_jumpers no)
		(fp_poly
			(pts
				(xy 0.3048 -0.1016) (xy 0.3048 0.9906) (xy -0.3048 0.9906) (xy -0.3048 -0.1016)
			)
			(stroke
				(width 0)
				(type default)
			)
			(fill no)
			(layer "F.CrtYd")
		)
		(fp_line
			(start -0.3048 0.9906)
			(end 0.3048 0.9906)
			(stroke
				(width 0.1)
				(type default)
			)
			(layer "F.Fab")
		)
		(fp_line
			(start 0.3048 0.9906)
			(end 0.3048 -0.1016)
			(stroke
				(width 0.1)
				(type default)
			)
			(layer "F.Fab")
		)
		(fp_line
			(start -0.3048 -0.1016)
			(end -0.3048 0.9906)
			(stroke
				(width 0.1)
				(type default)
			)
			(layer "F.Fab")
		)
		(fp_line
			(start 0.3048 -0.1016)
			(end -0.3048 -0.1016)
			(stroke
				(width 0.1)
				(type default)
			)
			(layer "F.Fab")
		)
		(pad "1" smd rect
			(at 0 0 270)
			(size 0.508 0.508)
			(layers "F.Cu" "F.Mask" "F.Paste")
			(net "P3E_CPU0_PE1_PCH_TXN<11>")
		)
		(pad "2" smd rect
			(at 0 0.889 270)
			(size 0.508 0.508)
			(layers "F.Cu" "F.Mask" "F.Paste")
			(net "P3E_CPU0_PE1_PCH_CON_TXN<11>")
		)
		(zone
			(layer "F.Cu")
			(hatch none 0.5)
			(connect_pads
				(clearance 0)
			)
			(min_thickness 0.25)
			(keepout
				(tracks not_allowed)
				(vias allowed)
				(pads allowed)
				(copperpour not_allowed)
				(footprints allowed)
			)
			(placement
				(enabled no)
				(sheetname "")
			)
			(fill
				(thermal_gap 0.5)
				(thermal_bridge_width 0.5)
				(island_removal_mode 0)
			)
			(polygon
				(pts
					(xy 322.3895 -117.476016) (xy 322.3895 -116.968016) (xy 322.7705 -116.968016) (xy 322.7705 -117.476016)
				)
			)
		)
		(zone
			(layer "F.Cu")
			(hatch none 0.5)
			(connect_pads
				(clearance 0)
			)
			(min_thickness 0.25)
			(keepout
				(tracks allowed)
				(vias not_allowed)
				(pads allowed)
				(copperpour not_allowed)
				(footprints allowed)
			)
			(placement
				(enabled no)
				(sheetname "")
			)
			(fill
				(thermal_gap 0.5)
				(thermal_bridge_width 0.5)
				(island_removal_mode 0)
			)
			(polygon
				(pts
					(xy 322.7705 -117.476016) (xy 322.7705 -116.968016) (xy 322.3895 -116.968016) (xy 322.3895 -117.476016)
				)
			)
		)
	)
)
